FILE_TYPE = MACRO_DRAWING;
SET COLOR_WIRE YELLOW;
SET COLOR_PROP ORANGE;
SET COLOR_DOT WHITE;
SET COLOR_ARC YELLOW;
SET COLOR_BODY GREEN;
SET COLOR_NOTE PURPLE;
SET PROP_DISPLAY VALUE;
SET PAGE_NUMBER P146;
FORCEADD P1V0_AUX..1
(-9175 5525);
FORCEPROP 3 LASTPIN (-9175 5475) SIG_NAME P12V_AUX\g
J 0
(-9165 5485);
DISPLAY 0.659574 (-9165 5485);
PAINT MONO (-9165 5485);
DISPLAY INVISIBLE (-9165 5485);
FORCEPROP 1 LAST HDL_POWER P12V_AUX
J 1
(-9164 5572);
DISPLAY 0.617021 (-9164 5572);
PAINT GREEN (-9164 5572);
FORCEPROP 2 LAST CDS_LIB pure_quanta_power
J 0
(-9175 5525);
DISPLAY INVISIBLE (-9175 5525);
FORCEPROP 1 LAST PATH I1
J 0
(-9125 5550);
DISPLAY 0.872340 (-9125 5550);
PAINT AQUA (-9125 5550);
DISPLAY INVISIBLE (-9125 5550);
FORCEADD MOSFET_PCH_GDS_ESD_PROTECTED..1
R 5
(-5750 4350);
FORCEPROP 1 LAST LOCATION Q7000
R 3
J 0
(-5325 4725);
DISPLAY 0.723404 (-5325 4725);
PAINT GREEN (-5325 4725);
FORCEPROP 2 LAST SEC 1
J 0
(-5450 4650);
DISPLAY 0.680851 (-5450 4650);
PAINT MONO (-5450 4650);
DISPLAY INVISIBLE (-5450 4650);
FORCEPROP 2 LASTPIN (-5450 4325) $PN D
J 0
(-5440 4335);
DISPLAY 0.680851 (-5440 4335);
PAINT MONO (-5440 4335);
FORCEPROP 2 LASTPIN (-5750 4625) $PN G
R 1
J 0
(-5760 4635);
DISPLAY 0.680851 (-5760 4635);
PAINT MONO (-5760 4635);
FORCEPROP 2 LASTPIN (-6050 4325) $PN S
J 2
(-6060 4335);
DISPLAY 0.680851 (-6060 4335);
PAINT MONO (-6060 4335);
FORCEPROP 2 LAST PART_TYPE SMLF
R 3
J 0
(-5231 4706);
DISPLAY 0.680851 (-5231 4706);
FORCEPROP 2 LAST VALUE DMP2035U-7
R 3
J 0
(-5281 4706);
DISPLAY 0.680851 (-5281 4706);
FORCEPROP 1 LAST MATERIAL EMPTY
R 3
J 0
(-5568 4519);
DISPLAY 0.723404 (-5568 4519);
PAINT GREEN (-5568 4519);
FORCEPROP 2 LAST CDS_LIB pure_quanta
R 3
J 0
(-5750 4350);
DISPLAY INVISIBLE (-5750 4350);
FORCEPROP 1 LAST CDS_LMAN_SYM_OUTLINE -125,150,125,-150
R 3
J 0
(-5750 4350);
DISPLAY 0.468085 (-5750 4350);
PAINT GREEN (-5750 4350);
DISPLAY INVISIBLE (-5750 4350);
FORCEPROP 2 LAST SEC_TYPE 
J 0
(-5450 4650);
DISPLAY 0.680851 (-5450 4650);
DISPLAY INVISIBLE (-5450 4650);
FORCEPROP 1 LAST NEEDS_NO_SIZE TRUE
R 3
J 0
(-5750 4350);
DISPLAY 0.723404 (-5750 4350);
PAINT GREEN (-5750 4350);
DISPLAY INVISIBLE (-5750 4350);
FORCEPROP 1 LAST PATH I10
R 3
J 0
(-5750 4350);
DISPLAY 0.723404 (-5750 4350);
PAINT GREEN (-5750 4350);
DISPLAY INVISIBLE (-5750 4350);
FORCEPROP 1 LAST PART_NUMBER BAM20350002
R 3
J 0
(-5425 4750);
DISPLAY 0.723404 (-5425 4750);
PAINT GREEN (-5425 4750);
DISPLAY INVISIBLE (-5425 4750);
FORCEADD Q_RES..2
(-8025 5075);
FORCEPROP 1 LAST LOCATION R1007
J 0
(-7980 5200);
DISPLAY 0.978723 (-7980 5200);
FORCEPROP 0 LAST $SEC 1
J 0
(-7975 5250);
DISPLAY 0.680851 (-7975 5250);
PAINT MONO (-7975 5250);
DISPLAY INVISIBLE (-7975 5250);
FORCEPROP 0 LAST CDS_SEC 1
J 0
(-7975 5250);
DISPLAY 0.680851 (-7975 5250);
DISPLAY INVISIBLE (-7975 5250);
FORCEPROP 1 LASTPIN (-8025 5175) $PN 1
J 0
(-8020 5137);
DISPLAY 0.787234 (-8020 5137);
PAINT MONO (-8020 5137);
FORCEPROP 1 LASTPIN (-8025 4975) $PN 2
J 0
(-8020 4985);
DISPLAY 0.787234 (-8020 4985);
PAINT MONO (-8020 4985);
FORCEPROP 1 LAST WATTAGE 1/16W
J 0
(-7985 5050);
DISPLAY 0.978723 (-7985 5050);
FORCEPROP 1 LAST TOLERANCE 1%
J 0
(-7980 5100);
DISPLAY 0.978723 (-7980 5100);
FORCEPROP 1 LAST VALUE 2K
J 0
(-7980 5150);
DISPLAY 0.978723 (-7980 5150);
FORCEPROP 1 LAST MATERIAL EMPTY
J 0
(-7985 5000);
DISPLAY 0.978723 (-7985 5000);
FORCEPROP 1 LAST PACK_TYPE 0402LF
J 0
(-7985 4900);
DISPLAY 0.978723 (-7985 4900);
FORCEPROP 2 LAST CDS_LIB pure_quanta
J 0
(-8025 5075);
DISPLAY INVISIBLE (-8025 5075);
FORCEPROP 1 LAST PATH I11
J 0
(-7975 5250);
DISPLAY 0.978723 (-7975 5250);
PAINT WHITE (-7975 5250);
DISPLAY INVISIBLE (-7975 5250);
FORCEPROP 1 LAST PART_NUMBER CS22002FB07
J 0
(-7985 4950);
DISPLAY 0.978723 (-7985 4950);
DISPLAY INVISIBLE (-7985 4950);
FORCEADD Q_RES..2
(-8025 3925);
FORCEPROP 1 LAST LOCATION R1049
J 0
(-7980 4050);
DISPLAY 0.978723 (-7980 4050);
FORCEPROP 0 LAST $SEC 1
J 0
(-7975 4100);
DISPLAY 0.680851 (-7975 4100);
PAINT MONO (-7975 4100);
DISPLAY INVISIBLE (-7975 4100);
FORCEPROP 0 LAST CDS_SEC 1
J 0
(-7975 4100);
DISPLAY 0.680851 (-7975 4100);
DISPLAY INVISIBLE (-7975 4100);
FORCEPROP 1 LASTPIN (-8025 4025) $PN 1
J 0
(-8020 3987);
DISPLAY 0.787234 (-8020 3987);
PAINT MONO (-8020 3987);
FORCEPROP 1 LASTPIN (-8025 3825) $PN 2
J 0
(-8020 3835);
DISPLAY 0.787234 (-8020 3835);
PAINT MONO (-8020 3835);
FORCEPROP 1 LAST TOLERANCE 1%
J 0
(-7980 3950);
DISPLAY 0.978723 (-7980 3950);
FORCEPROP 1 LAST VALUE 1K
J 0
(-7980 4000);
DISPLAY 0.978723 (-7980 4000);
FORCEPROP 1 LAST WATTAGE 1/16W
J 0
(-7985 3900);
DISPLAY 0.978723 (-7985 3900);
FORCEPROP 1 LAST MATERIAL EMPTY
J 0
(-7985 3850);
DISPLAY 0.978723 (-7985 3850);
FORCEPROP 1 LAST PACK_TYPE 0402LF
J 0
(-7985 3750);
DISPLAY 0.978723 (-7985 3750);
FORCEPROP 2 LAST CDS_LIB pure_quanta
J 0
(-8025 3925);
DISPLAY INVISIBLE (-8025 3925);
FORCEPROP 1 LAST PATH I12
J 0
(-7975 4100);
DISPLAY 0.978723 (-7975 4100);
PAINT WHITE (-7975 4100);
DISPLAY INVISIBLE (-7975 4100);
FORCEPROP 1 LAST PART_NUMBER CS21002FB06
J 0
(-7985 3800);
DISPLAY 0.978723 (-7985 3800);
DISPLAY INVISIBLE (-7985 3800);
FORCEADD UNIVERSAL_GND..1
R 2
(-8025 3425);
FORCEPROP 3 LASTPIN (-8025 3475) SIG_NAME GND\g
J 0
(-8015 3485);
DISPLAY 0.659574 (-8015 3485);
PAINT MONO (-8015 3485);
DISPLAY INVISIBLE (-8015 3485);
FORCEPROP 2 LAST CDS_LIB pure_quanta_power
J 0
(-8025 3425);
DISPLAY INVISIBLE (-8025 3425);
FORCEPROP 1 LAST HDL_POWER GND
J 1
(-8050 3350);
DISPLAY 0.872340 (-8050 3350);
PAINT GREEN (-8050 3350);
DISPLAY INVISIBLE (-8050 3350);
FORCEPROP 1 LAST PATH I13
J 2
(-8100 3425);
DISPLAY 0.872340 (-8100 3425);
PAINT AQUA (-8100 3425);
DISPLAY INVISIBLE (-8100 3425);
FORCEADD Q_RES..2
(-5200 3950);
FORCEPROP 1 LAST LOCATION R1474
J 0
(-5155 4075);
DISPLAY 0.978723 (-5155 4075);
FORCEPROP 0 LAST $SEC 1
J 0
(-5150 4125);
DISPLAY 0.680851 (-5150 4125);
PAINT MONO (-5150 4125);
DISPLAY INVISIBLE (-5150 4125);
FORCEPROP 0 LAST CDS_SEC 1
J 0
(-5150 4125);
DISPLAY 0.680851 (-5150 4125);
DISPLAY INVISIBLE (-5150 4125);
FORCEPROP 1 LASTPIN (-5200 4050) $PN 1
J 0
(-5195 4012);
DISPLAY 0.787234 (-5195 4012);
PAINT MONO (-5195 4012);
FORCEPROP 1 LASTPIN (-5200 3850) $PN 2
J 0
(-5195 3860);
DISPLAY 0.787234 (-5195 3860);
PAINT MONO (-5195 3860);
FORCEPROP 1 LAST VALUE 10K
J 0
(-5155 4025);
DISPLAY 0.978723 (-5155 4025);
FORCEPROP 1 LAST TOLERANCE 1%
J 0
(-5155 3975);
DISPLAY 0.978723 (-5155 3975);
FORCEPROP 1 LAST WATTAGE 1/16W
J 0
(-5160 3925);
DISPLAY 0.978723 (-5160 3925);
FORCEPROP 1 LAST PACK_TYPE 0402LF
J 0
(-5160 3775);
DISPLAY 0.978723 (-5160 3775);
FORCEPROP 1 LAST MATERIAL EMPTY
J 0
(-5160 3875);
DISPLAY 0.978723 (-5160 3875);
FORCEPROP 2 LAST CDS_LIB pure_quanta
J 0
(-5200 3950);
DISPLAY INVISIBLE (-5200 3950);
FORCEPROP 1 LAST PATH I14
J 0
(-5150 4125);
DISPLAY 0.978723 (-5150 4125);
PAINT WHITE (-5150 4125);
DISPLAY INVISIBLE (-5150 4125);
FORCEPROP 1 LAST PART_NUMBER CS31002FB08
J 0
(-5160 3825);
DISPLAY 0.978723 (-5160 3825);
DISPLAY INVISIBLE (-5160 3825);
FORCEADD UNIVERSAL_GND..1
R 2
(-5200 3525);
FORCEPROP 3 LASTPIN (-5200 3575) SIG_NAME GND\g
J 0
(-5190 3585);
DISPLAY 0.659574 (-5190 3585);
PAINT MONO (-5190 3585);
DISPLAY INVISIBLE (-5190 3585);
FORCEPROP 2 LAST CDS_LIB pure_quanta_power
J 0
(-5200 3525);
DISPLAY INVISIBLE (-5200 3525);
FORCEPROP 1 LAST HDL_POWER GND
J 1
(-5225 3450);
DISPLAY 0.872340 (-5225 3450);
PAINT GREEN (-5225 3450);
DISPLAY INVISIBLE (-5225 3450);
FORCEPROP 1 LAST PATH I15
J 2
(-5275 3525);
DISPLAY 0.872340 (-5275 3525);
PAINT AQUA (-5275 3525);
DISPLAY INVISIBLE (-5275 3525);
FORCEADD MOSFET_NCH_1D3S..1
R 6
(-4150 4375);
FORCEPROP 1 LAST LOCATION Q7001
J 0
(-3975 4400);
DISPLAY 0.723404 (-3975 4400);
PAINT GREEN (-3975 4400);
FORCEPROP 0 LAST $SEC 1
J 0
(-3975 4575);
DISPLAY 0.680851 (-3975 4575);
PAINT MONO (-3975 4575);
DISPLAY INVISIBLE (-3975 4575);
FORCEPROP 0 LAST CDS_SEC 1
J 0
(-3975 4575);
DISPLAY 0.680851 (-3975 4575);
DISPLAY INVISIBLE (-3975 4575);
FORCEPROP 0 LASTPIN (-4050 4125) $PN 1
R 1
J 2
(-4060 4115);
DISPLAY 0.680851 (-4060 4115);
PAINT MONO (-4060 4115);
FORCEPROP 0 LASTPIN (-4150 4125) $PN 2
R 1
J 2
(-4160 4115);
DISPLAY 0.680851 (-4160 4115);
PAINT MONO (-4160 4115);
FORCEPROP 0 LASTPIN (-4250 4125) $PN 3
R 1
J 2
(-4260 4115);
DISPLAY 0.680851 (-4260 4115);
PAINT MONO (-4260 4115);
FORCEPROP 0 LASTPIN (-4350 4325) $PN 4
J 2
(-4360 4335);
DISPLAY 0.680851 (-4360 4335);
PAINT MONO (-4360 4335);
FORCEPROP 0 LASTPIN (-4150 4625) $PN 5
R 1
J 0
(-4160 4635);
DISPLAY 0.680851 (-4160 4635);
PAINT MONO (-4160 4635);
FORCEPROP 2 LAST PART_TYPE SMLF
J 0
(-3975 4318);
DISPLAY 0.680851 (-3975 4318);
FORCEPROP 2 LAST VALUE PSMNR58-30YLH
J 0
(-3975 4368);
DISPLAY 0.680851 (-3975 4368);
FORCEPROP 1 LAST MATERIAL EMPTY
J 0
(-3998 4525);
DISPLAY 0.723404 (-3998 4525);
PAINT GREEN (-3998 4525);
FORCEPROP 2 LAST CDS_LIB pure_quanta
J 0
(-4150 4328);
DISPLAY INVISIBLE (-4150 4328);
FORCEPROP 1 LAST CDS_LMAN_SYM_OUTLINE -150,200,150,-200
J 0
(-4150 4353);
DISPLAY 0.468085 (-4150 4353);
PAINT GREEN (-4150 4353);
DISPLAY INVISIBLE (-4150 4353);
FORCEPROP 1 LAST NEEDS_NO_SIZE TRUE
J 0
(-4150 4354);
DISPLAY 0.468085 (-4150 4354);
PAINT GREEN (-4150 4354);
DISPLAY INVISIBLE (-4150 4354);
FORCEPROP 1 LAST PATH I16
J 0
(-4150 4341);
DISPLAY 0.723404 (-4150 4341);
PAINT GREEN (-4150 4341);
DISPLAY INVISIBLE (-4150 4341);
FORCEPROP 1 LAST PART_NUMBER BAMNR580000
J 0
(-3998 4466);
DISPLAY 0.723404 (-3998 4466);
PAINT GREEN (-3998 4466);
DISPLAY INVISIBLE (-3998 4466);
FORCEADD UNIVERSAL_GND..1
R 2
(-4150 3575);
FORCEPROP 3 LASTPIN (-4150 3625) SIG_NAME GND\g
J 0
(-4140 3635);
DISPLAY 0.659574 (-4140 3635);
PAINT MONO (-4140 3635);
DISPLAY INVISIBLE (-4140 3635);
FORCEPROP 2 LAST CDS_LIB pure_quanta_power
J 0
(-4150 3575);
DISPLAY INVISIBLE (-4150 3575);
FORCEPROP 1 LAST HDL_POWER GND
J 1
(-4175 3500);
DISPLAY 0.872340 (-4175 3500);
PAINT GREEN (-4175 3500);
DISPLAY INVISIBLE (-4175 3500);
FORCEPROP 1 LAST PATH I17
J 2
(-4225 3575);
DISPLAY 0.872340 (-4225 3575);
PAINT AQUA (-4225 3575);
DISPLAY INVISIBLE (-4225 3575);
FORCEADD P1V0_AUX..1
(-4150 5850);
FORCEPROP 3 LASTPIN (-4150 5800) SIG_NAME P12V_AUX\g
J 0
(-4140 5810);
DISPLAY 0.659574 (-4140 5810);
PAINT MONO (-4140 5810);
DISPLAY INVISIBLE (-4140 5810);
FORCEPROP 1 LAST HDL_POWER P12V_AUX
J 1
(-4139 5897);
DISPLAY 0.617021 (-4139 5897);
PAINT GREEN (-4139 5897);
FORCEPROP 2 LAST CDS_LIB pure_quanta_power
J 0
(-4150 5850);
DISPLAY INVISIBLE (-4150 5850);
FORCEPROP 1 LAST PATH I18
J 0
(-4100 5875);
DISPLAY 0.872340 (-4100 5875);
PAINT AQUA (-4100 5875);
DISPLAY INVISIBLE (-4100 5875);
FORCEADD Q_RES..2
(-4150 5350);
FORCEPROP 1 LAST LOCATION R1480
J 0
(-4105 5475);
DISPLAY 0.978723 (-4105 5475);
FORCEPROP 0 LAST $SEC 1
J 0
(-4100 5525);
DISPLAY 0.680851 (-4100 5525);
PAINT MONO (-4100 5525);
DISPLAY INVISIBLE (-4100 5525);
FORCEPROP 0 LAST CDS_SEC 1
J 0
(-4100 5525);
DISPLAY 0.680851 (-4100 5525);
DISPLAY INVISIBLE (-4100 5525);
FORCEPROP 1 LASTPIN (-4150 5450) $PN 1
J 0
(-4145 5412);
DISPLAY 0.787234 (-4145 5412);
PAINT MONO (-4145 5412);
FORCEPROP 1 LASTPIN (-4150 5250) $PN 2
J 0
(-4145 5260);
DISPLAY 0.787234 (-4145 5260);
PAINT MONO (-4145 5260);
FORCEPROP 1 LAST VALUE 10
J 0
(-4105 5425);
DISPLAY 0.978723 (-4105 5425);
FORCEPROP 1 LAST TOLERANCE 1%
J 0
(-4105 5375);
DISPLAY 0.978723 (-4105 5375);
FORCEPROP 1 LAST WATTAGE 2W
J 0
(-4110 5325);
DISPLAY 0.978723 (-4110 5325);
FORCEPROP 1 LAST MATERIAL EMPTY
J 0
(-4110 5275);
DISPLAY 0.978723 (-4110 5275);
FORCEPROP 1 LAST PACK_TYPE 2512LF
J 0
(-4110 5175);
DISPLAY 0.978723 (-4110 5175);
FORCEPROP 2 LAST CDS_LIB pure_quanta
J 0
(-4150 5350);
DISPLAY INVISIBLE (-4150 5350);
FORCEPROP 1 LAST PATH I19
J 0
(-4100 5525);
DISPLAY 0.978723 (-4100 5525);
PAINT WHITE (-4100 5525);
DISPLAY INVISIBLE (-4100 5525);
FORCEPROP 1 LAST PART_NUMBER CS0100AFR00
J 0
(-4110 5225);
DISPLAY 0.978723 (-4110 5225);
DISPLAY INVISIBLE (-4110 5225);
FORCEADD Q_RES..2
(-9175 5050);
FORCEPROP 1 LAST LOCATION R700
J 0
(-9130 5175);
DISPLAY 0.978723 (-9130 5175);
FORCEPROP 0 LAST $SEC 1
J 0
(-9125 5225);
DISPLAY 0.680851 (-9125 5225);
PAINT MONO (-9125 5225);
DISPLAY INVISIBLE (-9125 5225);
FORCEPROP 0 LAST CDS_SEC 1
J 0
(-9125 5225);
DISPLAY 0.680851 (-9125 5225);
DISPLAY INVISIBLE (-9125 5225);
FORCEPROP 1 LASTPIN (-9175 5150) $PN 1
J 0
(-9170 5112);
DISPLAY 0.787234 (-9170 5112);
PAINT MONO (-9170 5112);
FORCEPROP 1 LASTPIN (-9175 4950) $PN 2
J 0
(-9170 4960);
DISPLAY 0.787234 (-9170 4960);
PAINT MONO (-9170 4960);
FORCEPROP 1 LAST WATTAGE 1/16W
J 0
(-9135 5025);
DISPLAY 0.978723 (-9135 5025);
FORCEPROP 1 LAST TOLERANCE 1%
J 0
(-9130 5075);
DISPLAY 0.978723 (-9130 5075);
FORCEPROP 1 LAST VALUE 30K
J 0
(-9130 5125);
DISPLAY 0.978723 (-9130 5125);
FORCEPROP 1 LAST PACK_TYPE 0402LF
J 0
(-9135 4875);
DISPLAY 0.978723 (-9135 4875);
FORCEPROP 1 LAST MATERIAL EMPTY
J 0
(-9135 4975);
DISPLAY 0.978723 (-9135 4975);
FORCEPROP 2 LAST CDS_LIB pure_quanta
J 0
(-9175 5050);
DISPLAY INVISIBLE (-9175 5050);
FORCEPROP 1 LAST PATH I2
J 0
(-9125 5225);
DISPLAY 0.978723 (-9125 5225);
PAINT WHITE (-9125 5225);
DISPLAY INVISIBLE (-9125 5225);
FORCEPROP 1 LAST PART_NUMBER CS33002FB02
J 0
(-9135 4925);
DISPLAY 0.978723 (-9135 4925);
DISPLAY INVISIBLE (-9135 4925);
FORCEADD Q_RES..2
(-4025 2475);
FORCEPROP 1 LAST LOCATION R1481
J 0
(-3980 2600);
DISPLAY 0.978723 (-3980 2600);
FORCEPROP 0 LAST $SEC 1
J 0
(-3975 2650);
DISPLAY 0.680851 (-3975 2650);
PAINT MONO (-3975 2650);
DISPLAY INVISIBLE (-3975 2650);
FORCEPROP 0 LAST CDS_SEC 1
J 0
(-3975 2650);
DISPLAY 0.680851 (-3975 2650);
DISPLAY INVISIBLE (-3975 2650);
FORCEPROP 1 LASTPIN (-4025 2575) $PN 1
J 0
(-4020 2537);
DISPLAY 0.787234 (-4020 2537);
PAINT MONO (-4020 2537);
FORCEPROP 1 LASTPIN (-4025 2375) $PN 2
J 0
(-4020 2385);
DISPLAY 0.787234 (-4020 2385);
PAINT MONO (-4020 2385);
FORCEPROP 1 LAST WATTAGE 2W
J 0
(-3985 2450);
DISPLAY 0.978723 (-3985 2450);
FORCEPROP 1 LAST TOLERANCE 1%
J 0
(-3980 2500);
DISPLAY 0.978723 (-3980 2500);
FORCEPROP 1 LAST VALUE 10
J 0
(-3980 2550);
DISPLAY 0.978723 (-3980 2550);
FORCEPROP 1 LAST PACK_TYPE 2512LF
J 0
(-3985 2300);
DISPLAY 0.978723 (-3985 2300);
FORCEPROP 1 LAST MATERIAL EMPTY
J 0
(-3985 2400);
DISPLAY 0.978723 (-3985 2400);
FORCEPROP 2 LAST CDS_LIB pure_quanta
J 0
(-4025 2475);
DISPLAY INVISIBLE (-4025 2475);
FORCEPROP 1 LAST PATH I21
J 0
(-3975 2650);
DISPLAY 0.978723 (-3975 2650);
PAINT WHITE (-3975 2650);
DISPLAY INVISIBLE (-3975 2650);
FORCEPROP 1 LAST PART_NUMBER CS0100AFR00
J 0
(-3985 2350);
DISPLAY 0.978723 (-3985 2350);
DISPLAY INVISIBLE (-3985 2350);
FORCEADD MOSFET_NCH_1D3S..1
R 6
(-4025 1500);
FORCEPROP 1 LAST LOCATION Q7003
J 0
(-3850 1550);
DISPLAY 0.723404 (-3850 1550);
PAINT GREEN (-3850 1550);
FORCEPROP 0 LAST $SEC 1
J 0
(-3825 1700);
DISPLAY 0.680851 (-3825 1700);
PAINT MONO (-3825 1700);
DISPLAY INVISIBLE (-3825 1700);
FORCEPROP 0 LAST CDS_SEC 1
J 0
(-3825 1700);
DISPLAY 0.680851 (-3825 1700);
DISPLAY INVISIBLE (-3825 1700);
FORCEPROP 0 LASTPIN (-3925 1250) $PN 1
R 1
J 2
(-3935 1240);
DISPLAY 0.680851 (-3935 1240);
PAINT MONO (-3935 1240);
FORCEPROP 0 LASTPIN (-4025 1250) $PN 2
R 1
J 2
(-4035 1240);
DISPLAY 0.680851 (-4035 1240);
PAINT MONO (-4035 1240);
FORCEPROP 0 LASTPIN (-4125 1250) $PN 3
R 1
J 2
(-4135 1240);
DISPLAY 0.680851 (-4135 1240);
PAINT MONO (-4135 1240);
FORCEPROP 0 LASTPIN (-4225 1450) $PN 4
J 2
(-4235 1460);
DISPLAY 0.680851 (-4235 1460);
PAINT MONO (-4235 1460);
FORCEPROP 0 LASTPIN (-4025 1750) $PN 5
R 1
J 0
(-4035 1760);
DISPLAY 0.680851 (-4035 1760);
PAINT MONO (-4035 1760);
FORCEPROP 2 LAST PART_TYPE SMLF
J 0
(-3850 1443);
DISPLAY 0.680851 (-3850 1443);
FORCEPROP 2 LAST VALUE PSMNR58-30YLH
J 0
(-3850 1493);
DISPLAY 0.680851 (-3850 1493);
FORCEPROP 1 LAST MATERIAL EMPTY
J 0
(-3825 1650);
DISPLAY 0.723404 (-3825 1650);
PAINT GREEN (-3825 1650);
FORCEPROP 1 LAST NEEDS_NO_SIZE TRUE
J 0
(-4025 1479);
DISPLAY 0.468085 (-4025 1479);
PAINT GREEN (-4025 1479);
DISPLAY INVISIBLE (-4025 1479);
FORCEPROP 1 LAST CDS_LMAN_SYM_OUTLINE -150,200,150,-200
J 0
(-4025 1500);
DISPLAY 0.468085 (-4025 1500);
PAINT GREEN (-4025 1500);
DISPLAY INVISIBLE (-4025 1500);
FORCEPROP 2 LAST CDS_LIB pure_quanta
J 0
(-4025 1500);
DISPLAY INVISIBLE (-4025 1500);
FORCEPROP 1 LAST PATH I22
J 0
(-4025 1500);
DISPLAY 0.723404 (-4025 1500);
PAINT GREEN (-4025 1500);
DISPLAY INVISIBLE (-4025 1500);
FORCEPROP 1 LAST PART_NUMBER BAMNR580000
J 0
(-3850 1600);
DISPLAY 0.723404 (-3850 1600);
PAINT GREEN (-3850 1600);
DISPLAY INVISIBLE (-3850 1600);
FORCEADD MOSFET_PCH_GDS_ESD_PROTECTED..1
R 5
(-5625 1475);
FORCEPROP 1 LAST LOCATION Q7002
R 3
J 0
(-5225 1650);
DISPLAY 0.723404 (-5225 1650);
PAINT GREEN (-5225 1650);
FORCEPROP 0 LAST $SEC 1
J 0
(-5325 1775);
DISPLAY 0.680851 (-5325 1775);
PAINT MONO (-5325 1775);
DISPLAY INVISIBLE (-5325 1775);
FORCEPROP 0 LAST CDS_SEC 1
J 0
(-5325 1775);
DISPLAY 0.680851 (-5325 1775);
DISPLAY INVISIBLE (-5325 1775);
FORCEPROP 0 LASTPIN (-5325 1450) $PN D
J 0
(-5315 1460);
DISPLAY 0.680851 (-5315 1460);
PAINT MONO (-5315 1460);
FORCEPROP 0 LASTPIN (-5625 1750) $PN G
R 1
J 0
(-5635 1760);
DISPLAY 0.680851 (-5635 1760);
PAINT MONO (-5635 1760);
FORCEPROP 0 LASTPIN (-5925 1450) $PN S
J 2
(-5935 1460);
DISPLAY 0.680851 (-5935 1460);
PAINT MONO (-5935 1460);
FORCEPROP 2 LAST PART_TYPE SMLF
R 3
J 0
(-5075 1825);
DISPLAY 0.680851 (-5075 1825);
FORCEPROP 1 LAST MATERIAL EMPTY
R 3
J 0
(-5443 1644);
DISPLAY 0.723404 (-5443 1644);
PAINT GREEN (-5443 1644);
FORCEPROP 2 LAST VALUE DMP2035U-7
R 3
J 0
(-5125 1825);
DISPLAY 0.680851 (-5125 1825);
FORCEPROP 1 LAST NEEDS_NO_SIZE TRUE
R 3
J 0
(-5625 1475);
DISPLAY 0.723404 (-5625 1475);
PAINT GREEN (-5625 1475);
DISPLAY INVISIBLE (-5625 1475);
FORCEPROP 1 LAST CDS_LMAN_SYM_OUTLINE -125,150,125,-150
R 3
J 0
(-5625 1475);
DISPLAY 0.468085 (-5625 1475);
PAINT GREEN (-5625 1475);
DISPLAY INVISIBLE (-5625 1475);
FORCEPROP 2 LAST CDS_LIB pure_quanta
J 0
(-5625 1475);
DISPLAY INVISIBLE (-5625 1475);
FORCEPROP 1 LAST PATH I23
R 3
J 0
(-5625 1475);
DISPLAY 0.723404 (-5625 1475);
PAINT GREEN (-5625 1475);
DISPLAY INVISIBLE (-5625 1475);
FORCEPROP 1 LAST PART_NUMBER BAM20350002
R 3
J 0
(-5300 1875);
DISPLAY 0.723404 (-5300 1875);
PAINT GREEN (-5300 1875);
DISPLAY INVISIBLE (-5300 1875);
FORCEADD P1V0_AUX..1
(-7900 2650);
FORCEPROP 3 LASTPIN (-7900 2600) SIG_NAME P3V3_AUX\g
J 0
(-7890 2610);
DISPLAY 0.659574 (-7890 2610);
PAINT MONO (-7890 2610);
DISPLAY INVISIBLE (-7890 2610);
FORCEPROP 1 LAST HDL_POWER P3V3_AUX
J 1
(-7889 2697);
DISPLAY 0.617021 (-7889 2697);
PAINT GREEN (-7889 2697);
FORCEPROP 2 LAST CDS_LIB pure_quanta_power
J 0
(-7900 2650);
DISPLAY INVISIBLE (-7900 2650);
FORCEPROP 1 LAST PATH I24
J 0
(-7850 2675);
DISPLAY 0.872340 (-7850 2675);
PAINT AQUA (-7850 2675);
DISPLAY INVISIBLE (-7850 2675);
FORCEADD SCHOTTKY_DUAL_12A_3C..1
R 5
(-7250 1450);
FORCEPROP 1 LAST LOCATION U60
R 3
J 0
(-7219 1343);
DISPLAY 0.723404 (-7219 1343);
PAINT GREEN (-7219 1343);
FORCEPROP 0 LAST $SEC 1
J 0
(-7225 1775);
DISPLAY 0.680851 (-7225 1775);
PAINT MONO (-7225 1775);
DISPLAY INVISIBLE (-7225 1775);
FORCEPROP 0 LAST CDS_SEC 1
J 0
(-7225 1775);
DISPLAY 0.680851 (-7225 1775);
DISPLAY INVISIBLE (-7225 1775);
FORCEPROP 0 LASTPIN (-7350 1400) $PN 2
J 2
(-7360 1410);
DISPLAY 0.680851 (-7360 1410);
PAINT MONO (-7360 1410);
FORCEPROP 0 LASTPIN (-7350 1500) $PN 1
J 2
(-7360 1510);
DISPLAY 0.680851 (-7360 1510);
PAINT MONO (-7360 1510);
FORCEPROP 0 LASTPIN (-7150 1450) $PN 3
J 0
(-7140 1460);
DISPLAY 0.680851 (-7140 1460);
PAINT MONO (-7140 1460);
FORCEPROP 2 LAST PART_TYPE SMLF
J 0
(-7225 1725);
DISPLAY 1.021277 (-7225 1725);
FORCEPROP 2 LAST VALUE BAT54CW
J 0
(-7225 1675);
DISPLAY 0.765957 (-7225 1675);
PAINT SKYBLUE (-7225 1675);
FORCEPROP 1 LAST MATERIAL EMPTY
J 0
(-7225 1575);
DISPLAY 0.765957 (-7225 1575);
PAINT SKYBLUE (-7225 1575);
FORCEPROP 1 LAST NEEDS_NO_SIZE TRUE
R 3
J 0
(-7260 1350);
DISPLAY 0.723404 (-7260 1350);
PAINT GREEN (-7260 1350);
DISPLAY INVISIBLE (-7260 1350);
FORCEPROP 1 LAST CDS_LMAN_SYM_OUTLINE -100,50,100,-50
R 3
J 0
(-7250 1450);
DISPLAY 0.468085 (-7250 1450);
PAINT GREEN (-7250 1450);
DISPLAY INVISIBLE (-7250 1450);
FORCEPROP 2 LAST CDS_LIB pure_quanta
J 0
(-7250 1450);
DISPLAY INVISIBLE (-7250 1450);
FORCEPROP 1 LAST PATH I25
R 3
J 0
(-7300 1350);
DISPLAY 0.723404 (-7300 1350);
PAINT GREEN (-7300 1350);
DISPLAY INVISIBLE (-7300 1350);
FORCEPROP 1 LAST PART_NUMBER BCBAT54CZ13
J 0
(-7225 1625);
DISPLAY 0.765957 (-7225 1625);
PAINT SKYBLUE (-7225 1625);
DISPLAY INVISIBLE (-7225 1625);
FORCEADD UNIVERSAL_GND..1
R 2
(-4025 700);
FORCEPROP 3 LASTPIN (-4025 750) SIG_NAME GND\g
J 0
(-4015 760);
DISPLAY 0.659574 (-4015 760);
PAINT MONO (-4015 760);
DISPLAY INVISIBLE (-4015 760);
FORCEPROP 2 LAST CDS_LIB pure_quanta_power
J 0
(-4025 700);
DISPLAY INVISIBLE (-4025 700);
FORCEPROP 1 LAST HDL_POWER GND
J 1
(-4050 625);
DISPLAY 0.872340 (-4050 625);
PAINT GREEN (-4050 625);
DISPLAY INVISIBLE (-4050 625);
FORCEPROP 1 LAST PATH I27
J 2
(-4100 700);
DISPLAY 0.872340 (-4100 700);
PAINT AQUA (-4100 700);
DISPLAY INVISIBLE (-4100 700);
FORCEADD Q_RES..2
(-5075 1075);
FORCEPROP 1 LAST LOCATION R1475
J 0
(-5030 1200);
DISPLAY 0.978723 (-5030 1200);
FORCEPROP 0 LAST $SEC 1
J 0
(-5025 1250);
DISPLAY 0.680851 (-5025 1250);
PAINT MONO (-5025 1250);
DISPLAY INVISIBLE (-5025 1250);
FORCEPROP 0 LAST CDS_SEC 1
J 0
(-5025 1250);
DISPLAY 0.680851 (-5025 1250);
DISPLAY INVISIBLE (-5025 1250);
FORCEPROP 1 LASTPIN (-5075 1175) $PN 1
J 0
(-5070 1137);
DISPLAY 0.787234 (-5070 1137);
PAINT MONO (-5070 1137);
FORCEPROP 1 LASTPIN (-5075 975) $PN 2
J 0
(-5070 985);
DISPLAY 0.787234 (-5070 985);
PAINT MONO (-5070 985);
FORCEPROP 1 LAST PACK_TYPE 0402LF
J 0
(-5035 900);
DISPLAY 0.978723 (-5035 900);
FORCEPROP 1 LAST VALUE 10K
J 0
(-5030 1150);
DISPLAY 0.978723 (-5030 1150);
FORCEPROP 1 LAST TOLERANCE 1%
J 0
(-5030 1100);
DISPLAY 0.978723 (-5030 1100);
FORCEPROP 1 LAST WATTAGE 1/16W
J 0
(-5035 1050);
DISPLAY 0.978723 (-5035 1050);
FORCEPROP 1 LAST MATERIAL EMPTY
J 0
(-5035 1000);
DISPLAY 0.978723 (-5035 1000);
FORCEPROP 2 LAST CDS_LIB pure_quanta
J 0
(-5075 1075);
DISPLAY INVISIBLE (-5075 1075);
FORCEPROP 1 LAST PATH I28
J 0
(-5025 1250);
DISPLAY 0.978723 (-5025 1250);
PAINT WHITE (-5025 1250);
DISPLAY INVISIBLE (-5025 1250);
FORCEPROP 1 LAST PART_NUMBER CS31002FB08
J 0
(-5035 950);
DISPLAY 0.978723 (-5035 950);
DISPLAY INVISIBLE (-5035 950);
FORCEADD UNIVERSAL_GND..1
R 2
(-5075 650);
FORCEPROP 3 LASTPIN (-5075 700) SIG_NAME GND\g
J 0
(-5065 710);
DISPLAY 0.659574 (-5065 710);
PAINT MONO (-5065 710);
DISPLAY INVISIBLE (-5065 710);
FORCEPROP 2 LAST CDS_LIB pure_quanta_power
J 0
(-5075 650);
DISPLAY INVISIBLE (-5075 650);
FORCEPROP 1 LAST HDL_POWER GND
J 1
(-5100 575);
DISPLAY 0.872340 (-5100 575);
PAINT GREEN (-5100 575);
DISPLAY INVISIBLE (-5100 575);
FORCEPROP 1 LAST PATH I29
J 2
(-5150 650);
DISPLAY 0.872340 (-5150 650);
PAINT AQUA (-5150 650);
DISPLAY INVISIBLE (-5150 650);
FORCEADD Q_RES..2
(-9175 3900);
FORCEPROP 1 LAST LOCATION R855
J 0
(-9130 4025);
DISPLAY 0.978723 (-9130 4025);
FORCEPROP 0 LAST $SEC 1
J 0
(-9125 4075);
DISPLAY 0.680851 (-9125 4075);
PAINT MONO (-9125 4075);
DISPLAY INVISIBLE (-9125 4075);
FORCEPROP 0 LAST CDS_SEC 1
J 0
(-9125 4075);
DISPLAY 0.680851 (-9125 4075);
DISPLAY INVISIBLE (-9125 4075);
FORCEPROP 1 LASTPIN (-9175 4000) $PN 1
J 0
(-9170 3962);
DISPLAY 0.787234 (-9170 3962);
PAINT MONO (-9170 3962);
FORCEPROP 1 LASTPIN (-9175 3800) $PN 2
J 0
(-9170 3810);
DISPLAY 0.787234 (-9170 3810);
PAINT MONO (-9170 3810);
FORCEPROP 1 LAST WATTAGE 1/16W
J 0
(-9135 3875);
DISPLAY 0.978723 (-9135 3875);
FORCEPROP 1 LAST MATERIAL EMPTY
J 0
(-9135 3825);
DISPLAY 0.978723 (-9135 3825);
FORCEPROP 1 LAST TOLERANCE 1%
J 0
(-9130 3925);
DISPLAY 0.978723 (-9130 3925);
FORCEPROP 1 LAST VALUE 11.5K
J 0
(-9130 3975);
DISPLAY 0.978723 (-9130 3975);
FORCEPROP 1 LAST PACK_TYPE 0402LF
J 0
(-9135 3725);
DISPLAY 0.978723 (-9135 3725);
FORCEPROP 2 LAST CDS_LIB pure_quanta
J 0
(-9175 3900);
DISPLAY INVISIBLE (-9175 3900);
FORCEPROP 1 LAST PATH I3
J 0
(-9125 4075);
DISPLAY 0.978723 (-9125 4075);
PAINT WHITE (-9125 4075);
DISPLAY INVISIBLE (-9125 4075);
FORCEPROP 1 LAST PART_NUMBER CS31152FB03
J 0
(-9135 3775);
DISPLAY 0.978723 (-9135 3775);
DISPLAY INVISIBLE (-9135 3775);
FORCEADD Q_CAP..1
(-6750 950);
FORCEPROP 1 LAST LOCATION C1114
J 0
(-6700 1050);
DISPLAY 0.978723 (-6700 1050);
FORCEPROP 0 LAST $SEC 1
J 0
(-6700 1100);
DISPLAY 0.680851 (-6700 1100);
PAINT MONO (-6700 1100);
DISPLAY INVISIBLE (-6700 1100);
FORCEPROP 0 LAST CDS_SEC 1
J 0
(-6700 1100);
DISPLAY 0.680851 (-6700 1100);
DISPLAY INVISIBLE (-6700 1100);
FORCEPROP 1 LASTPIN (-6750 1050) $PN 1
J 0
(-6740 1030);
DISPLAY 0.787234 (-6740 1030);
PAINT MONO (-6740 1030);
FORCEPROP 1 LASTPIN (-6750 850) $PN 2
J 0
(-6740 830);
DISPLAY 0.787234 (-6740 830);
PAINT MONO (-6740 830);
FORCEPROP 1 LAST VALUE 22UF
J 0
(-6700 1000);
DISPLAY 0.978723 (-6700 1000);
FORCEPROP 1 LAST VOLTAGE 16V
J 0
(-6700 950);
DISPLAY 0.978723 (-6700 950);
FORCEPROP 1 LAST TOLERANCE 20%
J 0
(-6700 900);
DISPLAY 0.978723 (-6700 900);
FORCEPROP 1 LAST PACK_TYPE C0805
J 0
(-6700 750);
DISPLAY 0.978723 (-6700 750);
FORCEPROP 1 LAST MATERIAL EMPTY
J 0
(-6700 850);
DISPLAY 0.978723 (-6700 850);
FORCEPROP 2 LAST CDS_LIB pure_quanta
J 0
(-6750 950);
DISPLAY INVISIBLE (-6750 950);
FORCEPROP 1 LAST PATH I30
J 0
(-6700 1100);
DISPLAY 0.978723 (-6700 1100);
PAINT WHITE (-6700 1100);
DISPLAY INVISIBLE (-6700 1100);
FORCEPROP 1 LAST PART_NUMBER CH6223MEA00
J 0
(-6700 800);
DISPLAY 0.978723 (-6700 800);
DISPLAY INVISIBLE (-6700 800);
FORCEADD UNIVERSAL_GND..1
R 2
(-6750 600);
FORCEPROP 3 LASTPIN (-6750 650) SIG_NAME GND\g
J 0
(-6740 660);
DISPLAY 0.659574 (-6740 660);
PAINT MONO (-6740 660);
DISPLAY INVISIBLE (-6740 660);
FORCEPROP 2 LAST CDS_LIB pure_quanta_power
J 0
(-6750 600);
DISPLAY INVISIBLE (-6750 600);
FORCEPROP 1 LAST HDL_POWER GND
J 1
(-6775 525);
DISPLAY 0.872340 (-6775 525);
PAINT GREEN (-6775 525);
DISPLAY INVISIBLE (-6775 525);
FORCEPROP 1 LAST PATH I31
J 2
(-6825 600);
DISPLAY 0.872340 (-6825 600);
PAINT AQUA (-6825 600);
DISPLAY INVISIBLE (-6825 600);
FORCEADD UNIVERSAL_GND..1
R 2
(-7900 550);
FORCEPROP 3 LASTPIN (-7900 600) SIG_NAME GND\g
J 0
(-7890 610);
DISPLAY 0.659574 (-7890 610);
PAINT MONO (-7890 610);
DISPLAY INVISIBLE (-7890 610);
FORCEPROP 2 LAST CDS_LIB pure_quanta_power
J 0
(-7900 550);
DISPLAY INVISIBLE (-7900 550);
FORCEPROP 1 LAST HDL_POWER GND
J 1
(-7925 475);
DISPLAY 0.872340 (-7925 475);
PAINT GREEN (-7925 475);
DISPLAY INVISIBLE (-7925 475);
FORCEPROP 1 LAST PATH I33
J 2
(-7975 550);
DISPLAY 0.872340 (-7975 550);
PAINT AQUA (-7975 550);
DISPLAY INVISIBLE (-7975 550);
FORCEADD P1V0_AUX..1
(-9050 2650);
FORCEPROP 3 LASTPIN (-9050 2600) SIG_NAME P12V_AUX\g
J 0
(-9040 2610);
DISPLAY 0.659574 (-9040 2610);
PAINT MONO (-9040 2610);
DISPLAY INVISIBLE (-9040 2610);
FORCEPROP 1 LAST HDL_POWER P12V_AUX
J 1
(-9039 2697);
DISPLAY 0.617021 (-9039 2697);
PAINT GREEN (-9039 2697);
FORCEPROP 2 LAST CDS_LIB pure_quanta_power
J 0
(-9050 2650);
DISPLAY INVISIBLE (-9050 2650);
FORCEPROP 1 LAST PATH I34
J 0
(-9000 2675);
DISPLAY 0.872340 (-9000 2675);
PAINT AQUA (-9000 2675);
DISPLAY INVISIBLE (-9000 2675);
FORCEADD Q_RES..2
(-9050 2175);
FORCEPROP 1 LAST LOCATION R896
J 0
(-9005 2300);
DISPLAY 0.978723 (-9005 2300);
FORCEPROP 0 LAST $SEC 1
J 0
(-9000 2350);
DISPLAY 0.680851 (-9000 2350);
PAINT MONO (-9000 2350);
DISPLAY INVISIBLE (-9000 2350);
FORCEPROP 0 LAST CDS_SEC 1
J 0
(-9000 2350);
DISPLAY 0.680851 (-9000 2350);
DISPLAY INVISIBLE (-9000 2350);
FORCEPROP 1 LASTPIN (-9050 2275) $PN 1
J 0
(-9045 2237);
DISPLAY 0.787234 (-9045 2237);
PAINT MONO (-9045 2237);
FORCEPROP 1 LASTPIN (-9050 2075) $PN 2
J 0
(-9045 2085);
DISPLAY 0.787234 (-9045 2085);
PAINT MONO (-9045 2085);
FORCEPROP 1 LAST TOLERANCE 1%
J 0
(-9005 2200);
DISPLAY 0.978723 (-9005 2200);
FORCEPROP 1 LAST WATTAGE 1/16W
J 0
(-9010 2150);
DISPLAY 0.978723 (-9010 2150);
FORCEPROP 1 LAST VALUE 30K
J 0
(-9005 2250);
DISPLAY 0.978723 (-9005 2250);
FORCEPROP 1 LAST MATERIAL EMPTY
J 0
(-9010 2100);
DISPLAY 0.978723 (-9010 2100);
FORCEPROP 1 LAST PACK_TYPE 0402LF
J 0
(-9010 2000);
DISPLAY 0.978723 (-9010 2000);
FORCEPROP 2 LAST CDS_LIB pure_quanta
J 0
(-9050 2175);
DISPLAY INVISIBLE (-9050 2175);
FORCEPROP 1 LAST PATH I35
J 0
(-9000 2350);
DISPLAY 0.978723 (-9000 2350);
PAINT WHITE (-9000 2350);
DISPLAY INVISIBLE (-9000 2350);
FORCEPROP 1 LAST PART_NUMBER CS33002FB02
J 0
(-9010 2050);
DISPLAY 0.978723 (-9010 2050);
DISPLAY INVISIBLE (-9010 2050);
FORCEADD Q_RES..2
(-9050 1025);
FORCEPROP 1 LAST LOCATION R954
J 0
(-9005 1150);
DISPLAY 0.978723 (-9005 1150);
FORCEPROP 0 LAST $SEC 1
J 0
(-9000 1200);
DISPLAY 0.680851 (-9000 1200);
PAINT MONO (-9000 1200);
DISPLAY INVISIBLE (-9000 1200);
FORCEPROP 0 LAST CDS_SEC 1
J 0
(-9000 1200);
DISPLAY 0.680851 (-9000 1200);
DISPLAY INVISIBLE (-9000 1200);
FORCEPROP 1 LASTPIN (-9050 1125) $PN 1
J 0
(-9045 1087);
DISPLAY 0.787234 (-9045 1087);
PAINT MONO (-9045 1087);
FORCEPROP 1 LASTPIN (-9050 925) $PN 2
J 0
(-9045 935);
DISPLAY 0.787234 (-9045 935);
PAINT MONO (-9045 935);
FORCEPROP 1 LAST TOLERANCE 1%
J 0
(-9005 1050);
DISPLAY 0.978723 (-9005 1050);
FORCEPROP 1 LAST PACK_TYPE 0402LF
J 0
(-9010 850);
DISPLAY 0.978723 (-9010 850);
FORCEPROP 1 LAST VALUE 11.5K
J 0
(-9005 1100);
DISPLAY 0.978723 (-9005 1100);
FORCEPROP 1 LAST WATTAGE 1/16W
J 0
(-9010 1000);
DISPLAY 0.978723 (-9010 1000);
FORCEPROP 1 LAST MATERIAL EMPTY
J 0
(-9010 950);
DISPLAY 0.978723 (-9010 950);
FORCEPROP 2 LAST CDS_LIB pure_quanta
J 0
(-9050 1025);
DISPLAY INVISIBLE (-9050 1025);
FORCEPROP 1 LAST PATH I36
J 0
(-9000 1200);
DISPLAY 0.978723 (-9000 1200);
PAINT WHITE (-9000 1200);
DISPLAY INVISIBLE (-9000 1200);
FORCEPROP 1 LAST PART_NUMBER CS31152FB03
J 0
(-9010 900);
DISPLAY 0.978723 (-9010 900);
DISPLAY INVISIBLE (-9010 900);
FORCEADD UNIVERSAL_GND..1
R 2
(-9050 550);
FORCEPROP 3 LASTPIN (-9050 600) SIG_NAME GND\g
J 0
(-9040 610);
DISPLAY 0.659574 (-9040 610);
PAINT MONO (-9040 610);
DISPLAY INVISIBLE (-9040 610);
FORCEPROP 2 LAST CDS_LIB pure_quanta_power
J 0
(-9050 550);
DISPLAY INVISIBLE (-9050 550);
FORCEPROP 1 LAST HDL_POWER GND
J 1
(-9075 475);
DISPLAY 0.872340 (-9075 475);
PAINT GREEN (-9075 475);
DISPLAY INVISIBLE (-9075 475);
FORCEPROP 1 LAST PATH I37
J 2
(-9125 550);
DISPLAY 0.872340 (-9125 550);
PAINT AQUA (-9125 550);
DISPLAY INVISIBLE (-9125 550);
FORCEADD Q_RES..2
(-7900 2200);
FORCEPROP 1 LAST LOCATION R1052
J 0
(-7855 2325);
DISPLAY 0.978723 (-7855 2325);
FORCEPROP 0 LAST $SEC 1
J 0
(-7850 2375);
DISPLAY 0.680851 (-7850 2375);
PAINT MONO (-7850 2375);
DISPLAY INVISIBLE (-7850 2375);
FORCEPROP 0 LAST CDS_SEC 1
J 0
(-7850 2375);
DISPLAY 0.680851 (-7850 2375);
DISPLAY INVISIBLE (-7850 2375);
FORCEPROP 1 LASTPIN (-7900 2300) $PN 1
J 0
(-7895 2262);
DISPLAY 0.787234 (-7895 2262);
PAINT MONO (-7895 2262);
FORCEPROP 1 LASTPIN (-7900 2100) $PN 2
J 0
(-7895 2110);
DISPLAY 0.787234 (-7895 2110);
PAINT MONO (-7895 2110);
FORCEPROP 1 LAST WATTAGE 1/16W
J 0
(-7860 2175);
DISPLAY 0.978723 (-7860 2175);
FORCEPROP 1 LAST TOLERANCE 1%
J 0
(-7855 2225);
DISPLAY 0.978723 (-7855 2225);
FORCEPROP 1 LAST VALUE 1K
J 0
(-7855 2275);
DISPLAY 0.978723 (-7855 2275);
FORCEPROP 1 LAST MATERIAL EMPTY
J 0
(-7860 2125);
DISPLAY 0.978723 (-7860 2125);
FORCEPROP 1 LAST PACK_TYPE 0402LF
J 0
(-7860 2025);
DISPLAY 0.978723 (-7860 2025);
FORCEPROP 2 LAST CDS_LIB pure_quanta
J 0
(-7900 2200);
DISPLAY INVISIBLE (-7900 2200);
FORCEPROP 1 LAST PATH I38
J 0
(-7850 2375);
DISPLAY 0.978723 (-7850 2375);
PAINT WHITE (-7850 2375);
DISPLAY INVISIBLE (-7850 2375);
FORCEPROP 1 LAST PART_NUMBER CS21002FB06
J 0
(-7860 2075);
DISPLAY 0.978723 (-7860 2075);
DISPLAY INVISIBLE (-7860 2075);
FORCEADD Q_RES..2
(-7900 1050);
FORCEPROP 1 LAST LOCATION R1092
J 0
(-7855 1175);
DISPLAY 0.978723 (-7855 1175);
FORCEPROP 0 LAST $SEC 1
J 0
(-7850 1225);
DISPLAY 0.680851 (-7850 1225);
PAINT MONO (-7850 1225);
DISPLAY INVISIBLE (-7850 1225);
FORCEPROP 0 LAST CDS_SEC 1
J 0
(-7850 1225);
DISPLAY 0.680851 (-7850 1225);
DISPLAY INVISIBLE (-7850 1225);
FORCEPROP 1 LASTPIN (-7900 1150) $PN 1
J 0
(-7895 1112);
DISPLAY 0.787234 (-7895 1112);
PAINT MONO (-7895 1112);
FORCEPROP 1 LASTPIN (-7900 950) $PN 2
J 0
(-7895 960);
DISPLAY 0.787234 (-7895 960);
PAINT MONO (-7895 960);
FORCEPROP 1 LAST MATERIAL EMPTY
J 0
(-7860 975);
DISPLAY 0.978723 (-7860 975);
FORCEPROP 1 LAST WATTAGE 1/16W
J 0
(-7860 1025);
DISPLAY 0.978723 (-7860 1025);
FORCEPROP 1 LAST VALUE 10M
J 0
(-7855 1125);
DISPLAY 0.978723 (-7855 1125);
FORCEPROP 1 LAST TOLERANCE 1%
J 0
(-7855 1075);
DISPLAY 0.978723 (-7855 1075);
FORCEPROP 1 LAST PACK_TYPE 0402LF
J 0
(-7860 875);
DISPLAY 0.978723 (-7860 875);
FORCEPROP 2 LAST CDS_LIB pure_quanta
J 0
(-7900 1050);
DISPLAY INVISIBLE (-7900 1050);
FORCEPROP 1 LAST PATH I39
J 0
(-7850 1225);
DISPLAY 0.978723 (-7850 1225);
PAINT WHITE (-7850 1225);
DISPLAY INVISIBLE (-7850 1225);
FORCEPROP 1 LAST PART_NUMBER CS61002FB02
J 0
(-7860 925);
DISPLAY 0.978723 (-7860 925);
DISPLAY INVISIBLE (-7860 925);
FORCEADD UNIVERSAL_GND..1
R 2
(-9175 3425);
FORCEPROP 3 LASTPIN (-9175 3475) SIG_NAME GND\g
J 0
(-9165 3485);
DISPLAY 0.659574 (-9165 3485);
PAINT MONO (-9165 3485);
DISPLAY INVISIBLE (-9165 3485);
FORCEPROP 2 LAST CDS_LIB pure_quanta_power
J 0
(-9175 3425);
DISPLAY INVISIBLE (-9175 3425);
FORCEPROP 1 LAST HDL_POWER GND
J 1
(-9200 3350);
DISPLAY 0.872340 (-9200 3350);
PAINT GREEN (-9200 3350);
DISPLAY INVISIBLE (-9200 3350);
FORCEPROP 1 LAST PATH I4
J 2
(-9250 3425);
DISPLAY 0.872340 (-9250 3425);
PAINT AQUA (-9250 3425);
DISPLAY INVISIBLE (-9250 3425);
FORCEADD P1V0_AUX..1
(-4025 2975);
FORCEPROP 3 LASTPIN (-4025 2925) SIG_NAME P3V3_AUX\g
J 0
(-4015 2935);
DISPLAY 0.659574 (-4015 2935);
PAINT MONO (-4015 2935);
DISPLAY INVISIBLE (-4015 2935);
FORCEPROP 1 LAST HDL_POWER P3V3_AUX
J 1
(-4014 3022);
DISPLAY 0.617021 (-4014 3022);
PAINT GREEN (-4014 3022);
FORCEPROP 2 LAST CDS_LIB pure_quanta_power
J 0
(-4025 2975);
DISPLAY INVISIBLE (-4025 2975);
FORCEPROP 1 LAST PATH I40
J 0
(-3975 3000);
DISPLAY 0.872340 (-3975 3000);
PAINT AQUA (-3975 3000);
DISPLAY INVISIBLE (-3975 3000);
FORCEADD SCHOTTKY_DUAL_12A_3C..1
R 5
(-7375 4325);
FORCEPROP 1 LAST LOCATION U57
J 0
(-7350 4675);
DISPLAY 0.765957 (-7350 4675);
PAINT SKYBLUE (-7350 4675);
FORCEPROP 2 LAST SEC 1
J 0
(-7350 4725);
DISPLAY 0.680851 (-7350 4725);
PAINT MONO (-7350 4725);
DISPLAY INVISIBLE (-7350 4725);
FORCEPROP 2 LASTPIN (-7475 4275) $PN 2
J 2
(-7485 4285);
DISPLAY 0.680851 (-7485 4285);
PAINT MONO (-7485 4285);
FORCEPROP 2 LASTPIN (-7475 4375) $PN 1
J 2
(-7485 4385);
DISPLAY 0.680851 (-7485 4385);
PAINT MONO (-7485 4385);
FORCEPROP 2 LASTPIN (-7275 4325) $PN 3
J 0
(-7265 4335);
DISPLAY 0.680851 (-7265 4335);
PAINT MONO (-7265 4335);
FORCEPROP 2 LAST VALUE BAT54CW
J 0
(-7350 4550);
DISPLAY 0.765957 (-7350 4550);
PAINT SKYBLUE (-7350 4550);
FORCEPROP 1 LAST MATERIAL EMPTY
J 0
(-7350 4450);
DISPLAY 0.765957 (-7350 4450);
PAINT SKYBLUE (-7350 4450);
FORCEPROP 2 LAST PART_TYPE SMLF
J 0
(-7350 4600);
DISPLAY 1.021277 (-7350 4600);
FORCEPROP 1 LAST CDS_LMAN_SYM_OUTLINE -100,50,100,-50
R 3
J 0
(-7375 4325);
DISPLAY 0.468085 (-7375 4325);
PAINT GREEN (-7375 4325);
DISPLAY INVISIBLE (-7375 4325);
FORCEPROP 2 LAST CDS_LIB pure_quanta
J 0
(-7375 4325);
DISPLAY INVISIBLE (-7375 4325);
FORCEPROP 2 LAST SEC_TYPE 
J 0
(-7350 4725);
DISPLAY 0.680851 (-7350 4725);
DISPLAY INVISIBLE (-7350 4725);
FORCEPROP 1 LAST NEEDS_NO_SIZE TRUE
R 3
J 0
(-7385 4225);
DISPLAY 0.723404 (-7385 4225);
PAINT GREEN (-7385 4225);
DISPLAY INVISIBLE (-7385 4225);
FORCEPROP 1 LAST PATH I5
R 3
J 0
(-7425 4225);
DISPLAY 0.723404 (-7425 4225);
PAINT GREEN (-7425 4225);
DISPLAY INVISIBLE (-7425 4225);
FORCEPROP 1 LAST PART_NUMBER BCBAT54CZ13
J 0
(-7350 4500);
DISPLAY 0.765957 (-7350 4500);
PAINT SKYBLUE (-7350 4500);
DISPLAY INVISIBLE (-7350 4500);
FORCEADD Q_CAP..1
(-6875 3825);
FORCEPROP 1 LAST LOCATION C1113
J 0
(-6825 3925);
DISPLAY 0.978723 (-6825 3925);
FORCEPROP 0 LAST $SEC 1
J 0
(-6825 3975);
DISPLAY 0.680851 (-6825 3975);
PAINT MONO (-6825 3975);
DISPLAY INVISIBLE (-6825 3975);
FORCEPROP 0 LAST CDS_SEC 1
J 0
(-6825 3975);
DISPLAY 0.680851 (-6825 3975);
DISPLAY INVISIBLE (-6825 3975);
FORCEPROP 1 LASTPIN (-6875 3925) $PN 1
J 0
(-6865 3905);
DISPLAY 0.787234 (-6865 3905);
PAINT MONO (-6865 3905);
FORCEPROP 1 LASTPIN (-6875 3725) $PN 2
J 0
(-6865 3705);
DISPLAY 0.787234 (-6865 3705);
PAINT MONO (-6865 3705);
FORCEPROP 1 LAST VALUE 22UF
J 0
(-6825 3875);
DISPLAY 0.978723 (-6825 3875);
FORCEPROP 1 LAST VOLTAGE 16V
J 0
(-6825 3825);
DISPLAY 0.978723 (-6825 3825);
FORCEPROP 1 LAST TOLERANCE 20%
J 0
(-6825 3775);
DISPLAY 0.978723 (-6825 3775);
FORCEPROP 1 LAST MATERIAL EMPTY
J 0
(-6825 3725);
DISPLAY 0.978723 (-6825 3725);
FORCEPROP 1 LAST PACK_TYPE C0805
J 0
(-6825 3625);
DISPLAY 0.978723 (-6825 3625);
FORCEPROP 2 LAST CDS_LIB pure_quanta
J 0
(-6875 3825);
DISPLAY INVISIBLE (-6875 3825);
FORCEPROP 1 LAST PATH I6
J 0
(-6825 3975);
DISPLAY 0.978723 (-6825 3975);
PAINT WHITE (-6825 3975);
DISPLAY INVISIBLE (-6825 3975);
FORCEPROP 1 LAST PART_NUMBER CH6223MEA00
J 0
(-6825 3675);
DISPLAY 0.978723 (-6825 3675);
DISPLAY INVISIBLE (-6825 3675);
FORCEADD UNIVERSAL_GND..1
R 2
(-6875 3475);
FORCEPROP 3 LASTPIN (-6875 3525) SIG_NAME GND\g
J 0
(-6865 3535);
DISPLAY 0.659574 (-6865 3535);
PAINT MONO (-6865 3535);
DISPLAY INVISIBLE (-6865 3535);
FORCEPROP 2 LAST CDS_LIB pure_quanta_power
J 0
(-6875 3475);
DISPLAY INVISIBLE (-6875 3475);
FORCEPROP 1 LAST HDL_POWER GND
J 1
(-6900 3400);
DISPLAY 0.872340 (-6900 3400);
PAINT GREEN (-6900 3400);
DISPLAY INVISIBLE (-6900 3400);
FORCEPROP 1 LAST PATH I7
J 2
(-6950 3475);
DISPLAY 0.872340 (-6950 3475);
PAINT AQUA (-6950 3475);
DISPLAY INVISIBLE (-6950 3475);
FORCEADD P1V0_AUX..1
(-8025 5525);
FORCEPROP 3 LASTPIN (-8025 5475) SIG_NAME P12V_AUX\g
J 0
(-8015 5485);
DISPLAY 0.659574 (-8015 5485);
PAINT MONO (-8015 5485);
DISPLAY INVISIBLE (-8015 5485);
FORCEPROP 1 LAST HDL_POWER P12V_AUX
J 1
(-8014 5572);
DISPLAY 0.617021 (-8014 5572);
PAINT GREEN (-8014 5572);
FORCEPROP 2 LAST CDS_LIB pure_quanta_power
J 0
(-8025 5525);
DISPLAY INVISIBLE (-8025 5525);
FORCEPROP 1 LAST PATH I9
J 0
(-7975 5550);
DISPLAY 0.872340 (-7975 5550);
PAINT AQUA (-7975 5550);
DISPLAY INVISIBLE (-7975 5550);
FORCEADD DNS..2
(-3975 1500);
PAINT RED (-3975 1500);
FORCEPROP 2 LAST CDS_LIB mstr_misc
J 0
(-3975 1500);
DISPLAY INVISIBLE (-3975 1500);
FORCEPROP 1 LAST COMMENT_BODY TRUE
R 1
J 0
(-3900 1275);
DISPLAY 0.872340 (-3900 1275);
PAINT GREEN (-3900 1275);
DISPLAY INVISIBLE (-3900 1275);
FORCEADD DNS..2
(-4100 4375);
PAINT RED (-4100 4375);
FORCEPROP 2 LAST CDS_LIB mstr_misc
J 0
(-4100 4375);
DISPLAY INVISIBLE (-4100 4375);
FORCEPROP 1 LAST COMMENT_BODY TRUE
R 1
J 0
(-4025 4150);
DISPLAY 0.872340 (-4025 4150);
PAINT GREEN (-4025 4150);
DISPLAY INVISIBLE (-4025 4150);
FORCEADD DNS..2
(-5075 3925);
PAINT RED (-5075 3925);
FORCEPROP 2 LAST CDS_LIB mstr_misc
J 0
(-5075 3925);
DISPLAY INVISIBLE (-5075 3925);
FORCEPROP 1 LAST COMMENT_BODY TRUE
R 1
J 0
(-5000 3700);
DISPLAY 0.872340 (-5000 3700);
PAINT GREEN (-5000 3700);
DISPLAY INVISIBLE (-5000 3700);
FORCEADD DNS..2
(-3950 2400);
PAINT RED (-3950 2400);
FORCEPROP 2 LAST CDS_LIB mstr_misc
J 0
(-3950 2400);
DISPLAY INVISIBLE (-3950 2400);
FORCEPROP 1 LAST COMMENT_BODY TRUE
R 1
J 0
(-3875 2175);
DISPLAY 0.872340 (-3875 2175);
PAINT GREEN (-3875 2175);
DISPLAY INVISIBLE (-3875 2175);
FORCEADD DNS..2
(-5750 4275);
PAINT RED (-5750 4275);
FORCEPROP 2 LAST CDS_LIB mstr_misc
J 0
(-5750 4275);
DISPLAY INVISIBLE (-5750 4275);
FORCEPROP 1 LAST COMMENT_BODY TRUE
R 1
J 0
(-5675 4050);
DISPLAY 0.872340 (-5675 4050);
PAINT GREEN (-5675 4050);
DISPLAY INVISIBLE (-5675 4050);
FORCEADD DNS..2
(-4075 5325);
PAINT RED (-4075 5325);
FORCEPROP 2 LAST CDS_LIB mstr_misc
J 0
(-4075 5325);
DISPLAY INVISIBLE (-4075 5325);
FORCEPROP 1 LAST COMMENT_BODY TRUE
R 1
J 0
(-4000 5100);
DISPLAY 0.872340 (-4000 5100);
PAINT GREEN (-4000 5100);
DISPLAY INVISIBLE (-4000 5100);
FORCEADD DNS..2
(-4950 1050);
PAINT RED (-4950 1050);
FORCEPROP 2 LAST CDS_LIB mstr_misc
J 0
(-4950 1050);
DISPLAY INVISIBLE (-4950 1050);
FORCEPROP 1 LAST COMMENT_BODY TRUE
R 1
J 0
(-4875 825);
DISPLAY 0.872340 (-4875 825);
PAINT GREEN (-4875 825);
DISPLAY INVISIBLE (-4875 825);
FORCEADD DNS..2
(-5625 1500);
PAINT RED (-5625 1500);
FORCEPROP 2 LAST CDS_LIB mstr_misc
J 0
(-5625 1500);
DISPLAY INVISIBLE (-5625 1500);
FORCEPROP 1 LAST COMMENT_BODY TRUE
R 1
J 0
(-5550 1275);
DISPLAY 0.872340 (-5550 1275);
PAINT GREEN (-5550 1275);
DISPLAY INVISIBLE (-5550 1275);
FORCEADD DNS..2
(-7300 4475);
PAINT RED (-7300 4475);
FORCEPROP 2 LAST CDS_LIB mstr_misc
J 0
(-7300 4475);
DISPLAY INVISIBLE (-7300 4475);
FORCEPROP 1 LAST COMMENT_BODY TRUE
R 1
J 0
(-7225 4250);
DISPLAY 0.872340 (-7225 4250);
PAINT GREEN (-7225 4250);
DISPLAY INVISIBLE (-7225 4250);
FORCEADD DNS..2
(-6650 925);
PAINT RED (-6650 925);
FORCEPROP 2 LAST CDS_LIB mstr_misc
J 0
(-6650 925);
DISPLAY INVISIBLE (-6650 925);
FORCEPROP 1 LAST COMMENT_BODY TRUE
R 1
J 0
(-6575 700);
DISPLAY 0.872340 (-6575 700);
PAINT GREEN (-6575 700);
DISPLAY INVISIBLE (-6575 700);
FORCEADD DNS..2
(-6775 3775);
PAINT RED (-6775 3775);
FORCEPROP 2 LAST CDS_LIB mstr_misc
J 0
(-6775 3775);
DISPLAY INVISIBLE (-6775 3775);
FORCEPROP 1 LAST COMMENT_BODY TRUE
R 1
J 0
(-6700 3550);
DISPLAY 0.872340 (-6700 3550);
PAINT GREEN (-6700 3550);
DISPLAY INVISIBLE (-6700 3550);
FORCEADD DNS..2
(-7150 1575);
PAINT RED (-7150 1575);
FORCEPROP 2 LAST CDS_LIB mstr_misc
J 0
(-7150 1575);
DISPLAY INVISIBLE (-7150 1575);
FORCEPROP 1 LAST COMMENT_BODY TRUE
R 1
J 0
(-7075 1350);
DISPLAY 0.872340 (-7075 1350);
PAINT GREEN (-7075 1350);
DISPLAY INVISIBLE (-7075 1350);
FORCEADD DNS..2
(-7900 3925);
PAINT RED (-7900 3925);
FORCEPROP 2 LAST CDS_LIB mstr_misc
J 0
(-7900 3925);
DISPLAY INVISIBLE (-7900 3925);
FORCEPROP 1 LAST COMMENT_BODY TRUE
R 1
J 0
(-7825 3700);
DISPLAY 0.872340 (-7825 3700);
PAINT GREEN (-7825 3700);
DISPLAY INVISIBLE (-7825 3700);
FORCEADD DNS..2
(-7825 2150);
PAINT RED (-7825 2150);
FORCEPROP 2 LAST CDS_LIB mstr_misc
J 0
(-7825 2150);
DISPLAY INVISIBLE (-7825 2150);
FORCEPROP 1 LAST COMMENT_BODY TRUE
R 1
J 0
(-7750 1925);
DISPLAY 0.872340 (-7750 1925);
PAINT GREEN (-7750 1925);
DISPLAY INVISIBLE (-7750 1925);
FORCEADD DNS..2
(-7925 5075);
PAINT RED (-7925 5075);
FORCEPROP 2 LAST CDS_LIB mstr_misc
J 0
(-7925 5075);
DISPLAY INVISIBLE (-7925 5075);
FORCEPROP 1 LAST COMMENT_BODY TRUE
R 1
J 0
(-7850 4850);
DISPLAY 0.872340 (-7850 4850);
PAINT GREEN (-7850 4850);
DISPLAY INVISIBLE (-7850 4850);
FORCEADD DNS..2
(-9075 3875);
PAINT RED (-9075 3875);
FORCEPROP 2 LAST CDS_LIB mstr_misc
J 0
(-9075 3875);
DISPLAY INVISIBLE (-9075 3875);
FORCEPROP 1 LAST COMMENT_BODY TRUE
R 1
J 0
(-9000 3650);
DISPLAY 0.872340 (-9000 3650);
PAINT GREEN (-9000 3650);
DISPLAY INVISIBLE (-9000 3650);
FORCEADD DNS..2
(-8975 1000);
PAINT RED (-8975 1000);
FORCEPROP 2 LAST CDS_LIB mstr_misc
J 0
(-8975 1000);
DISPLAY INVISIBLE (-8975 1000);
FORCEPROP 1 LAST COMMENT_BODY TRUE
R 1
J 0
(-8900 775);
DISPLAY 0.872340 (-8900 775);
PAINT GREEN (-8900 775);
DISPLAY INVISIBLE (-8900 775);
FORCEADD DNS..2
(-9075 5075);
PAINT RED (-9075 5075);
FORCEPROP 2 LAST CDS_LIB mstr_misc
J 0
(-9075 5075);
DISPLAY INVISIBLE (-9075 5075);
FORCEPROP 1 LAST COMMENT_BODY TRUE
R 1
J 0
(-9000 4850);
DISPLAY 0.872340 (-9000 4850);
PAINT GREEN (-9000 4850);
DISPLAY INVISIBLE (-9000 4850);
FORCEADD DNS..2
(-8950 2200);
PAINT RED (-8950 2200);
FORCEPROP 2 LAST CDS_LIB mstr_misc
J 0
(-8950 2200);
DISPLAY INVISIBLE (-8950 2200);
FORCEPROP 1 LAST COMMENT_BODY TRUE
R 1
J 0
(-8875 1975);
DISPLAY 0.872340 (-8875 1975);
PAINT GREEN (-8875 1975);
DISPLAY INVISIBLE (-8875 1975);
FORCEADD DNS..2
(-7825 1025);
PAINT RED (-7825 1025);
FORCEPROP 2 LAST CDS_LIB mstr_misc
J 0
(-7825 1025);
DISPLAY INVISIBLE (-7825 1025);
FORCEPROP 1 LAST COMMENT_BODY TRUE
R 1
J 0
(-7750 800);
DISPLAY 0.872340 (-7750 800);
PAINT GREEN (-7750 800);
DISPLAY INVISIBLE (-7750 800);
FORCEADD QUANTA_TITLE_BLOCK_C..1
(-575 -600);
FORCEPROP 0 LAST CDS_CON_LAST_MODIFIED Thu Sep 14 16:13:12 2023
J 0
(-2460 -585);
DISPLAY INVISIBLE (-2460 -585);
FORCEPROP 1 LAST CUSTOM_TXT_CDS <CON_LAST_MODIFIED>
J 0
(-2460 -585);
DISPLAY 0.978723 (-2460 -585);
FORCEPROP 2 LAST CUSTOM_TXT_CDS <XR_PAGE_TITLE>
J 0
(-8465 4650);
DISPLAY 0.638298 (-8465 4650);
PAINT PINK (-8465 4650);
DISPLAY INVISIBLE (-8465 4650);
FORCEPROP 1 LAST CUSTOM_TXT_CDS <NAME_2>
J 0
(-3750 -550);
FORCEPROP 1 LAST CUSTOM_TXT_CDS <NAME_1>
J 0
(-3750 -425);
FORCEPROP 1 LAST CUSTOM_TXT_CDS <Q_NUMBER>
J 0
(-1978 -497);
DISPLAY 1.212766 (-1978 -497);
FORCEPROP 1 LAST CUSTOM_TXT_CDS <Q_PROJ>
J 0
(-2957 -498);
DISPLAY 1.212766 (-2957 -498);
FORCEPROP 1 LAST CUSTOM_TXT_CDS <Q_REV>
J 0
(-759 -497);
DISPLAY 1.212766 (-759 -497);
FORCEPROP 1 LAST CUSTOM_TXT_CDS <CON_PAGE_NUM> OF <CON_TOTAL_PAGES>
J 0
(-1021 -582);
DISPLAY 0.978723 (-1021 -582);
FORCEPROP 1 LAST Q_TITLE DISCHARGE CIRCUIT
J 0
(-9850 -550);
DISPLAY 2.446809 (-9850 -550);
PAINT GREEN (-9850 -550);
FORCEPROP 2 LAST CDS_XR_PAGE_TITLE CR-169 : @T6G_MB_LIB.T6G(SCH_1):PAGE169
J 0
(-8465 4650);
DISPLAY 0.638298 (-8465 4650);
PAINT PINK (-8465 4650);
DISPLAY INVISIBLE (-8465 4650);
FORCEPROP 2 LAST PAGE_BORDER TRUE
J 0
(-8465 4650);
DISPLAY 0.638298 (-8465 4650);
PAINT PINK (-8465 4650);
DISPLAY INVISIBLE (-8465 4650);
FORCEPROP 1 LAST CDS_LMAN_SYM_OUTLINE -9475,6775,100,-125
J 0
(-575 -600);
DISPLAY 0.468085 (-575 -600);
PAINT GREEN (-575 -600);
DISPLAY INVISIBLE (-575 -600);
FORCEPROP 2 LAST CDS_LIB pure_quanta
J 0
(-575 -600);
DISPLAY INVISIBLE (-575 -600);
FORCEPROP 1 LAST Q_DEPT BU9
J 1
(-4338 -551);
DISPLAY 1.957447 (-4338 -551);
PAINT GREEN (-4338 -551);
DISPLAY INVISIBLE (-4338 -551);
FORCEPROP 1 LAST COMMENT_BODY TRUE
J 0
(-563 -613);
DISPLAY 0.978723 (-563 -613);
PAINT GREEN (-563 -613);
DISPLAY INVISIBLE (-563 -613);
WIRE 16 -1 (-9175 5475)(-9175 5150);
WIRE 16 -1 (-8025 3825)(-8025 3475);
WIRE 16 -1 (-5200 3850)(-5200 3575);
WIRE 16 -1 (-4150 5450)(-4150 5800);
WIRE 16 -1 (-7900 2600)(-7900 2300);
WIRE 16 -1 (-5075 975)(-5075 700);
WIRE 16 -1 (-6750 850)(-6750 650);
WIRE 16 -1 (-7900 950)(-7900 600);
WIRE 16 -1 (-9050 2600)(-9050 2275);
WIRE 16 -1 (-9050 925)(-9050 600);
WIRE 16 -1 (-9175 3800)(-9175 3475);
WIRE 16 -1 (-4025 2575)(-4025 2925);
WIRE 16 -1 (-6875 3725)(-6875 3525);
WIRE 16 -1 (-8025 5475)(-8025 5175);
WIRE 16 -1 (-4025 1750)(-4025 2375);
FORCEPROP 2 LAST SIG_NAME P3V3_AUX_DSC
J 0
(-3985 2060);
DISPLAY 0.680851 (-3985 2060);
FORCEPROP 2 LASTPROP $XRERR UNIQUE?
J 0
(-4225 2060);
DISPLAY 0.638298 (-4225 2060);
PAINT MONO (-4225 2060);
DISPLAY INVISIBLE (-4225 2060);
WIRE 16 -1 (-5075 1175)(-5075 1450);
WIRE 16 -1 (-5075 1450)(-4225 1450);
FORCEPROP 2 LAST SIG_NAME P3V3_AUX_DSC_G2
J 0
(-4885 1460);
DISPLAY 0.680851 (-4885 1460);
FORCEPROP 2 LASTPROP $XRERR UNIQUE?
J 0
(-5125 1460);
DISPLAY 0.638298 (-5125 1460);
PAINT MONO (-5125 1460);
DISPLAY INVISIBLE (-5125 1460);
WIRE 16 -1 (-5325 1450)(-5075 1450);
WIRE 16 -1 (-6750 1450)(-5925 1450);
FORCEPROP 2 LAST SIG_NAME P3V3_AUX_DSC_S1
J 0
(-6535 1460);
DISPLAY 0.680851 (-6535 1460);
FORCEPROP 2 LASTPROP $XRERR UNIQUE?
J 0
(-6775 1460);
DISPLAY 0.638298 (-6775 1460);
PAINT MONO (-6775 1460);
DISPLAY INVISIBLE (-6775 1460);
WIRE 16 -1 (-6750 1450)(-6750 1050);
WIRE 16 -1 (-7150 1450)(-6750 1450);
WIRE 16 -1 (-7350 1500)(-9050 1500);
FORCEPROP 2 LAST SIG_NAME P3V3_AUX_DSC_VOL
J 0
(-8810 1510);
DISPLAY 0.680851 (-8810 1510);
FORCEPROP 2 LASTPROP $XRERR UNIQUE?
J 0
(-9050 1510);
DISPLAY 0.638298 (-9050 1510);
PAINT MONO (-9050 1510);
DISPLAY INVISIBLE (-9050 1510);
WIRE 16 -1 (-9050 2075)(-9050 1500);
WIRE 16 -1 (-9050 1500)(-9050 1125);
WIRE 16 -1 (-7900 1975)(-5625 1975);
FORCEPROP 2 LAST SIG_NAME P3V3_AUX_DSC_G1
J 0
(-6585 1985);
DISPLAY 0.680851 (-6585 1985);
FORCEPROP 2 LASTPROP $XRERR UNIQUE?
J 0
(-6825 1985);
DISPLAY 0.638298 (-6825 1985);
PAINT MONO (-6825 1985);
DISPLAY INVISIBLE (-6825 1985);
WIRE 16 -1 (-7900 2100)(-7900 1975);
WIRE 16 -1 (-7900 1975)(-7900 1150);
WIRE 16 -1 (-5625 1975)(-5625 1750);
WIRE 16 -1 (-5450 4325)(-5200 4325);
WIRE 16 -1 (-5200 4325)(-4350 4325);
FORCEPROP 2 LAST SIG_NAME P12V_AUX_DSC_G2
J 0
(-5060 4335);
DISPLAY 0.680851 (-5060 4335);
FORCEPROP 2 LASTPROP $XRERR UNIQUE?
J 0
(-5300 4335);
DISPLAY 0.638298 (-5300 4335);
PAINT MONO (-5300 4335);
DISPLAY INVISIBLE (-5300 4335);
WIRE 16 -1 (-5200 4050)(-5200 4325);
WIRE 16 -1 (-4150 4625)(-4150 5250);
FORCEPROP 2 LAST SIG_NAME P12V_AUX_DSC
J 0
(-4110 4935);
DISPLAY 0.680851 (-4110 4935);
FORCEPROP 2 LASTPROP $XRERR UNIQUE?
J 0
(-4350 4935);
DISPLAY 0.638298 (-4350 4935);
PAINT MONO (-4350 4935);
DISPLAY INVISIBLE (-4350 4935);
WIRE 16 -1 (-6875 4325)(-6050 4325);
FORCEPROP 2 LAST SIG_NAME P12V_AUX_DSC_S1
J 0
(-6810 4335);
DISPLAY 0.680851 (-6810 4335);
FORCEPROP 2 LASTPROP $XRERR UNIQUE?
J 0
(-7050 4335);
DISPLAY 0.638298 (-7050 4335);
PAINT MONO (-7050 4335);
DISPLAY INVISIBLE (-7050 4335);
WIRE 16 -1 (-7275 4325)(-6875 4325);
WIRE 16 -1 (-6875 4325)(-6875 3925);
WIRE 16 -1 (-7475 4375)(-9175 4375);
FORCEPROP 2 LAST SIG_NAME P12V_AUX_DSC_VOL
J 0
(-8760 4385);
DISPLAY 0.680851 (-8760 4385);
FORCEPROP 2 LASTPROP $XRERR UNIQUE?
J 0
(-9000 4385);
DISPLAY 0.638298 (-9000 4385);
PAINT MONO (-9000 4385);
DISPLAY INVISIBLE (-9000 4385);
WIRE 16 -1 (-9175 4950)(-9175 4375);
WIRE 16 -1 (-9175 4375)(-9175 4000);
WIRE 16 -1 (-8025 4850)(-5750 4850);
FORCEPROP 2 LAST SIG_NAME P12V_AUX_DSC_G1
J 0
(-6860 4860);
DISPLAY 0.680851 (-6860 4860);
FORCEPROP 2 LASTPROP $XRERR UNIQUE?
J 0
(-7100 4860);
DISPLAY 0.638298 (-7100 4860);
PAINT MONO (-7100 4860);
DISPLAY INVISIBLE (-7100 4860);
WIRE 16 -1 (-8025 4975)(-8025 4850);
WIRE 16 -1 (-8025 4850)(-8025 4025);
WIRE 16 -1 (-5750 4850)(-5750 4625);
WIRE 16 -1 (-4125 1250)(-4125 950);
WIRE 16 -1 (-4125 950)(-4025 950);
WIRE 16 -1 (-3925 950)(-4025 950);
WIRE 16 -1 (-4025 1250)(-4025 950);
WIRE 16 -1 (-4025 950)(-4025 750);
WIRE 16 -1 (-3925 1250)(-3925 950);
WIRE 16 -1 (-4250 4125)(-4250 3825);
WIRE 16 -1 (-4250 3825)(-4150 3825);
WIRE 16 -1 (-4050 3825)(-4150 3825);
WIRE 16 -1 (-4150 4125)(-4150 3825);
WIRE 16 -1 (-4150 3825)(-4150 3625);
WIRE 16 -1 (-4050 4125)(-4050 3825);
DOT 1 (-5075 1450);
DOT 1 (-6750 1450);
DOT 1 (-8025 4850);
DOT 1 (-6875 4325);
DOT 1 (-5200 4325);
DOT 1 (-7900 1975);
DOT 1 (-4150 3825);
DOT 1 (-9175 4375);
DOT 1 (-9050 1500);
DOT 1 (-4025 950);
FORCENOTE
VTH(MAX)=2.2V
(-3825 1325) 0;
DISPLAY LEFT (-3825 1325);
DISPLAY 1.021277 (-3825 1325);
FORCENOTE
VTH(MAX)=1V
(-5875 1200) 0;
DISPLAY LEFT (-5875 1200);
DISPLAY 1.021277 (-5875 1200);
FORCENOTE
P12V_AUX DISCHARGE
(-6800 3100) 0;
DISPLAY LEFT (-6800 3100);
DISPLAY 2.000000 (-6800 3100);
FORCENOTE
VTH(MAX)=1V
(-6000 4075) 0;
DISPLAY LEFT (-6000 4075);
DISPLAY 1.021277 (-6000 4075);
FORCENOTE
VTH(MAX)=2.2V
(-3950 4200) 0;
DISPLAY LEFT (-3950 4200);
DISPLAY 1.021277 (-3950 4200);
FORCENOTE
P3V3_AUX DISCHARGE
(-6600 0) 0;
DISPLAY LEFT (-6600 0);
DISPLAY 2.000000 (-6600 0);
QUIT
